# BASEBOARD_FAB2 (Tioga Pass) — schematic netlist excerpt (pin names and nets, part order shuffled) for the footprints in the layout excerpt that follows; sources: Cadence DE-HDL packaged netlist, KiCad conversion of Wiwynn_Tioga_Pass_MB.brd

C7F18  CAP_A  1.0UF 6.3V 10% X6S  pkg 0402V  page 215 : A = VR_PVDDQ_ABC_VDD ; B = GND
R25W154  RES  0.0 5% CHIP  pkg 0402  page 137 : A = SPI_BMC_BT_WP0_N ; B = TPM_SPI_BMC_WP_N
C2D2  CAP_A  22.0UF 4V 20% X6S  pkg 0603V  page 228 : A = PVDDQ_KLM ; B = GND

(kicad_pcb
	(version 20260206)
	(generator "pcbnew")
	(generator_version "10.0")
	(general
		(thickness 1.6)
		(legacy_teardrops no)
	)
	(paper "A4")
	(title_block
		(title "Wiwynn_Tioga_Pass_MB.brd")
		(comment 1 "Tioga Pass / footprints 1100-1102 of 4770")
	)
	(layers
		(0 "F.Cu" signal "TOP")
		(4 "In1.Cu" signal "L2GND")
		(6 "In2.Cu" signal "L3")
		(8 "In3.Cu" signal "L4GND")
		(10 "In4.Cu" signal "L5")
		(12 "In5.Cu" signal "L6GND")
		(14 "In6.Cu" signal "L7VCC")
		(16 "In7.Cu" signal "L8VCC")
		(18 "In8.Cu" signal "L9GND")
		(20 "In9.Cu" signal "L10")
		(22 "In10.Cu" signal "L11GND")
		(24 "In11.Cu" signal "L12")
		(26 "In12.Cu" signal "L13GND")
		(2 "B.Cu" signal "BOTTOM")
		(9 "F.Adhes" user "F.Adhesive")
		(11 "B.Adhes" user "B.Adhesive")
		(13 "F.Paste" user "Package Geometry/Pastemask Top")
		(15 "B.Paste" user "Package Geometry/Pastemask Bottom")
		(5 "F.SilkS" user "Ref Des/Silkscreen Top")
		(7 "B.SilkS" user "Ref Des/Silkscreen Bottom")
		(1 "F.Mask" user "Board Geometry/Soldermask Top")
		(3 "B.Mask" user "Board Geometry/Soldermask Bottom")
		(17 "Dwgs.User" user "User.Drawings")
		(19 "Cmts.User" user "User.Comments")
		(21 "Eco1.User" user "User.Eco1")
		(23 "Eco2.User" user "User.Eco2")
		(25 "Edge.Cuts" user "Board Geometry/Outline")
		(27 "Margin" user)
		(31 "F.CrtYd" user "Package Geometry/Place Bound Top")
		(29 "B.CrtYd" user "Package Geometry/Place Bound Bottom")
		(35 "F.Fab" user "Ref Des/Assembly Top")
		(33 "B.Fab" user "Ref Des/Assembly Bottom")
	)
	(footprint ""
		(layer "F.Cu")
		(at 465.6074 -1.9558)
		(property "Reference" "R25W154"
			(at -0.8382 -0.67818 0)
			(unlocked yes)
			(layer "F.SilkS")
			(effects
				(font
					(size 0.4064 0.254)
					(thickness 0.1524)
				)
				(justify left)
			)
		)
		(property "Value" ""
			(at 0 0 0)
			(layer "F.Fab")
			(effects
				(font
					(size 1.27 1.27)
				)
			)
		)
		(duplicate_pad_numbers_are_jumpers no)
		(fp_poly
			(pts
				(xy -0.2794 -0.1016) (xy 0.2794 -0.1016) (xy 0.2794 0.9906) (xy -0.2794 0.9906)
			)
			(stroke
				(width 0)
				(type default)
			)
			(fill no)
			(layer "F.CrtYd")
		)
		(fp_line
			(start -0.2794 -0.1016)
			(end -0.2794 0.9906)
			(stroke
				(width 0.1)
				(type default)
			)
			(layer "F.Fab")
		)
		(fp_line
			(start -0.2794 0.9906)
			(end 0.2794 0.9906)
			(stroke
				(width 0.1)
				(type default)
			)
			(layer "F.Fab")
		)
		(fp_line
			(start 0.2794 -0.1016)
			(end -0.2794 -0.1016)
			(stroke
				(width 0.1)
				(type default)
			)
			(layer "F.Fab")
		)
		(fp_line
			(start 0.2794 0.9906)
			(end 0.2794 -0.1016)
			(stroke
				(width 0.1)
				(type default)
			)
			(layer "F.Fab")
		)
		(pad "1" smd rect
			(at 0 0)
			(size 0.508 0.508)
			(layers "F.Cu" "F.Mask" "F.Paste")
			(net "SPI_BMC_BT_WP0_N")
		)
		(pad "2" smd rect
			(at 0 0.889)
			(size 0.508 0.508)
			(layers "F.Cu" "F.Mask" "F.Paste")
			(net "TPM_SPI_BMC_WP_N")
		)
		(zone
			(layer "F.Cu")
			(hatch none 0.5)
			(connect_pads
				(clearance 0)
			)
			(min_thickness 0.25)
			(keepout
				(tracks allowed)
				(vias not_allowed)
				(pads allowed)
				(copperpour not_allowed)
				(footprints allowed)
			)
			(placement
				(enabled no)
				(sheetname "")
			)
			(fill
				(thermal_gap 0.5)
				(thermal_bridge_width 0.5)
				(island_removal_mode 0)
			)
			(polygon
				(pts
					(xy 465.3534 -1.7018) (xy 465.8614 -1.7018) (xy 465.8614 -1.3208) (xy 465.3534 -1.3208)
				)
			)
		)
		(zone
			(layer "F.Cu")
			(hatch none 0.5)
			(connect_pads
				(clearance 0)
			)
			(min_thickness 0.25)
			(keepout
				(tracks not_allowed)
				(vias allowed)
				(pads allowed)
				(copperpour not_allowed)
				(footprints allowed)
			)
			(placement
				(enabled no)
				(sheetname "")
			)
			(fill
				(thermal_gap 0.5)
				(thermal_bridge_width 0.5)
				(island_removal_mode 0)
			)
			(polygon
				(pts
					(xy 465.3534 -1.3208) (xy 465.8614 -1.3208) (xy 465.8614 -1.7018) (xy 465.3534 -1.7018)
				)
			)
		)
	)
	(footprint ""
		(layer "F.Cu")
		(at 104.751378 -84.890102)
		(property "Reference" "C2D2"
			(at 0 0 0)
			(layer "F.SilkS")
			(hide yes)
			(effects
				(font
					(size 1.27 1.27)
				)
			)
		)
		(property "Value" ""
			(at 0 0 0)
			(layer "F.Fab")
			(effects
				(font
					(size 1.27 1.27)
				)
			)
		)
		(duplicate_pad_numbers_are_jumpers no)
		(fp_poly
			(pts
				(xy -0.4953 -0.2032) (xy 0.4953 -0.2032) (xy 0.4953 1.6002) (xy -0.4953 1.6002)
			)
			(stroke
				(width 0)
				(type default)
			)
			(fill no)
			(layer "F.CrtYd")
		)
		(fp_line
			(start -0.4953 -0.2032)
			(end 0.4953 -0.2032)
			(stroke
				(width 0.1)
				(type default)
			)
			(layer "F.Fab")
		)
		(fp_line
			(start -0.4953 1.6002)
			(end -0.4953 -0.2032)
			(stroke
				(width 0.1)
				(type default)
			)
			(layer "F.Fab")
		)
		(fp_line
			(start 0.4953 -0.2032)
			(end 0.4953 1.6002)
			(stroke
				(width 0.1)
				(type default)
			)
			(layer "F.Fab")
		)
		(fp_line
			(start 0.4953 1.6002)
			(end -0.4953 1.6002)
			(stroke
				(width 0.1)
				(type default)
			)
			(layer "F.Fab")
		)
		(pad "1" smd rect
			(at 0 0)
			(size 0.762 0.889)
			(layers "F.Cu" "F.Mask" "F.Paste")
			(net "PVDDQ_KLM")
		)
		(pad "2" smd rect
			(at 0 1.397)
			(size 0.762 0.889)
			(layers "F.Cu" "F.Mask" "F.Paste")
			(net "GND")
		)
		(zone
			(layer "F.Cu")
			(hatch none 0.5)
			(connect_pads
				(clearance 0)
			)
			(min_thickness 0.25)
			(keepout
				(tracks not_allowed)
				(vias allowed)
				(pads allowed)
				(copperpour not_allowed)
				(footprints allowed)
			)
			(placement
				(enabled no)
				(sheetname "")
			)
			(fill
				(thermal_gap 0.5)
				(thermal_bridge_width 0.5)
				(island_removal_mode 0)
			)
			(polygon
				(pts
					(xy 104.370378 -84.445602) (xy 105.132378 -84.445602) (xy 105.132378 -83.937602) (xy 104.370378 -83.937602)
				)
			)
		)
	)
	(footprint ""
		(layer "F.Cu")
		(at 350.012 -17.78 180)
		(property "Reference" "C7F18"
			(at 0 0 180)
			(layer "F.SilkS")
			(hide yes)
			(effects
				(font
					(size 1.27 1.27)
				)
			)
		)
		(property "Value" ""
			(at 0 0 180)
			(layer "F.Fab")
			(effects
				(font
					(size 1.27 1.27)
				)
			)
		)
		(duplicate_pad_numbers_are_jumpers no)
		(fp_poly
			(pts
				(xy 0.3048 -0.1016) (xy 0.3048 0.9906) (xy -0.3048 0.9906) (xy -0.3048 -0.1016)
			)
			(stroke
				(width 0)
				(type default)
			)
			(fill no)
			(layer "F.CrtYd")
		)
		(fp_line
			(start 0.3048 0.9906)
			(end 0.3048 -0.1016)
			(stroke
				(width 0.1)
				(type default)
			)
			(layer "F.Fab")
		)
		(fp_line
			(start 0.3048 -0.1016)
			(end -0.3048 -0.1016)
			(stroke
				(width 0.1)
				(type default)
			)
			(layer "F.Fab")
		)
		(fp_line
			(start -0.3048 0.9906)
			(end 0.3048 0.9906)
			(stroke
				(width 0.1)
				(type default)
			)
			(layer "F.Fab")
		)
		(fp_line
			(start -0.3048 -0.1016)
			(end -0.3048 0.9906)
			(stroke
				(width 0.1)
				(type default)
			)
			(layer "F.Fab")
		)
		(pad "1" smd rect
			(at 0 0 180)
			(size 0.508 0.508)
			(layers "F.Cu" "F.Mask" "F.Paste")
			(net "VR_PVDDQ_ABC_VDD")
		)
		(pad "2" smd rect
			(at 0 0.889 180)
			(size 0.508 0.508)
			(layers "F.Cu" "F.Mask" "F.Paste")
			(net "GND")
		)
		(zone
			(layer "F.Cu")
			(hatch none 0.5)
			(connect_pads
				(clearance 0)
			)
			(min_thickness 0.25)
			(keepout
				(tracks not_allowed)
				(vias allowed)
				(pads allowed)
				(copperpour not_allowed)
				(footprints allowed)
			)
			(placement
				(enabled no)
				(sheetname "")
			)
			(fill
				(thermal_gap 0.5)
				(thermal_bridge_width 0.5)
				(island_removal_mode 0)
			)
			(polygon
				(pts
					(xy 350.266 -18.415) (xy 349.758 -18.415) (xy 349.758 -18.034) (xy 350.266 -18.034)
				)
			)
		)
		(zone
			(layer "F.Cu")
			(hatch none 0.5)
			(connect_pads
				(clearance 0)
			)
			(min_thickness 0.25)
			(keepout
				(tracks allowed)
				(vias not_allowed)
				(pads allowed)
				(copperpour not_allowed)
				(footprints allowed)
			)
			(placement
				(enabled no)
				(sheetname "")
			)
			(fill
				(thermal_gap 0.5)
				(thermal_bridge_width 0.5)
				(island_removal_mode 0)
			)
			(polygon
				(pts
					(xy 350.266 -18.034) (xy 349.758 -18.034) (xy 349.758 -18.415) (xy 350.266 -18.415)
				)
			)
		)
	)
)
